# T6G (Grand Teton) — schematic netlist excerpt (pin names and nets, part order shuffled) for the footprints in the layout excerpt that follows; sources: Cadence DE-HDL packaged netlist, KiCad conversion of 04192023_DAF0TMB3IC0_F0TG_MB_C_brd_V02_OCP.brd

C3908  Q_CAP  22UF 4V 20% X6S  pkg C0402  page 72 : A = PVDDCR_SOC_P1 ; B = GND
C464  Q_CAP  0.1UF 10V 10% X7S  pkg C0201  page 356 : A = P0V9_CPU1_RT3_2A_2D ; B = GND

Q78  MOSFET_NCH_DUAL  PJT138K IC  pkg SOT363XD  page 254
  S1  = GND
  G1  = PWRGD_P1V8_AUX_R
  D2  = LED_PWRGD_PS_PWROK_PLD_D
  S2  = GND
  G2  = PWRGD_PS_PWROK_PLD
  D1  = LED_PWRGD_P1V8_AUX_D

(kicad_pcb
	(version 20260206)
	(generator "pcbnew")
	(generator_version "10.0")
	(general
		(thickness 1.6)
		(legacy_teardrops no)
	)
	(paper "A4")
	(title_block
		(title "04192023_DAF0TMB3IC0_F0TG_MB_C_brd_V02_OCP.brd")
		(comment 1 "Grand Teton / footprints 5173-5175 of 8354")
	)
	(layers
		(0 "F.Cu" signal "TOP")
		(4 "In1.Cu" signal "GND")
		(6 "In2.Cu" signal "IN1")
		(8 "In3.Cu" signal "GND1")
		(10 "In4.Cu" signal "IN2")
		(12 "In5.Cu" signal "GND2")
		(14 "In6.Cu" signal "IN3")
		(16 "In7.Cu" signal "GND3")
		(18 "In8.Cu" signal "VCC")
		(20 "In9.Cu" signal "VCC1")
		(22 "In10.Cu" signal "GND4")
		(24 "In11.Cu" signal "IN4")
		(26 "In12.Cu" signal "GND5")
		(28 "In13.Cu" signal "IN5")
		(30 "In14.Cu" signal "GND6")
		(32 "In15.Cu" signal "IN6")
		(34 "In16.Cu" signal "GND7")
		(2 "B.Cu" signal "BOTTOM")
		(9 "F.Adhes" user "F.Adhesive")
		(11 "B.Adhes" user "B.Adhesive")
		(13 "F.Paste" user "Package Geometry/Pastemask Top")
		(15 "B.Paste" user "Package Geometry/Pastemask Bottom")
		(5 "F.SilkS" user "Ref Des/Silkscreen Top")
		(7 "B.SilkS" user "Ref Des/Silkscreen Bottom")
		(1 "F.Mask" user "Board Geometry/Soldermask Top")
		(3 "B.Mask" user "Board Geometry/Soldermask Bottom")
		(17 "Dwgs.User" user "User.Drawings")
		(19 "Cmts.User" user "User.Comments")
		(21 "Eco1.User" user "User.Eco1")
		(23 "Eco2.User" user "User.Eco2")
		(25 "Edge.Cuts" user "Board Geometry/Outline")
		(27 "Margin" user)
		(31 "F.CrtYd" user "Package Geometry/Place Bound Top")
		(29 "B.CrtYd" user "Package Geometry/Place Bound Bottom")
		(35 "F.Fab" user "Ref Des/Assembly Top")
		(33 "B.Fab" user "Ref Des/Assembly Bottom")
	)
	(footprint ""
		(layer "B.Cu")
		(at 113.375948 -256.012442 -90)
		(property "Reference" "C3908"
			(at 0 0 90)
			(layer "B.SilkS")
			(hide yes)
			(effects
				(font
					(size 1.27 1.27)
				)
				(justify mirror)
			)
		)
		(property "Value" ""
			(at 0 0 90)
			(layer "B.Fab")
			(effects
				(font
					(size 1.27 1.27)
				)
				(justify mirror)
			)
		)
		(duplicate_pad_numbers_are_jumpers no)
		(fp_line
			(start -0.7874 0.4064)
			(end 0.7874 0.4064)
			(stroke
				(width 0.1524)
				(type default)
			)
			(layer "B.SilkS")
		)
		(fp_line
			(start 0.7874 0.4064)
			(end 0.7874 -0.4064)
			(stroke
				(width 0.1524)
				(type default)
			)
			(layer "B.SilkS")
		)
		(fp_line
			(start -0.7874 -0.4064)
			(end -0.7874 0.4064)
			(stroke
				(width 0.1524)
				(type default)
			)
			(layer "B.SilkS")
		)
		(fp_line
			(start 0.7874 -0.4064)
			(end -0.7874 -0.4064)
			(stroke
				(width 0.1524)
				(type default)
			)
			(layer "B.SilkS")
		)
		(fp_line
			(start -0.67945 0.3048)
			(end -0.120396 0.3048)
			(stroke
				(width 0.1)
				(type default)
			)
			(layer "B.Fab")
		)
		(fp_line
			(start -0.120396 0.3048)
			(end -0.120396 0.2794)
			(stroke
				(width 0.1)
				(type default)
			)
			(layer "B.Fab")
		)
		(fp_line
			(start 0.12065 0.3048)
			(end 0.67945 0.3048)
			(stroke
				(width 0.1)
				(type default)
			)
			(layer "B.Fab")
		)
		(fp_line
			(start 0.67945 0.3048)
			(end 0.67945 -0.305054)
			(stroke
				(width 0.1)
				(type default)
			)
			(layer "B.Fab")
		)
		(fp_line
			(start -0.120396 0.2794)
			(end 0.12065 0.2794)
			(stroke
				(width 0.1)
				(type default)
			)
			(layer "B.Fab")
		)
		(fp_line
			(start 0.12065 0.2794)
			(end 0.12065 0.3048)
			(stroke
				(width 0.1)
				(type default)
			)
			(layer "B.Fab")
		)
		(fp_line
			(start -0.12065 -0.2794)
			(end -0.12065 -0.3048)
			(stroke
				(width 0.1)
				(type default)
			)
			(layer "B.Fab")
		)
		(fp_line
			(start 0.12065 -0.2794)
			(end -0.12065 -0.2794)
			(stroke
				(width 0.1)
				(type default)
			)
			(layer "B.Fab")
		)
		(fp_line
			(start -0.67945 -0.3048)
			(end -0.67945 0.3048)
			(stroke
				(width 0.1)
				(type default)
			)
			(layer "B.Fab")
		)
		(fp_line
			(start -0.12065 -0.3048)
			(end -0.67945 -0.3048)
			(stroke
				(width 0.1)
				(type default)
			)
			(layer "B.Fab")
		)
		(fp_line
			(start 0.12065 -0.305054)
			(end 0.12065 -0.2794)
			(stroke
				(width 0.1)
				(type default)
			)
			(layer "B.Fab")
		)
		(fp_line
			(start 0.67945 -0.305054)
			(end 0.12065 -0.305054)
			(stroke
				(width 0.1)
				(type default)
			)
			(layer "B.Fab")
		)
		(pad "1" smd circle
			(at 0.40005 0 90)
			(size 0 0)
			(layers "B.Cu" "B.Mask" "B.Paste")
			(net "PVDDCR_SOC_P1")
		)
		(pad "2" smd circle
			(at -0.40005 0 90)
			(size 0 0)
			(layers "B.Cu" "B.Mask" "B.Paste")
			(net "GND")
		)
	)
	(footprint ""
		(layer "B.Cu")
		(at 127.818388 -388.011162 -90)
		(property "Reference" "C464"
			(at 0 0 90)
			(layer "B.SilkS")
			(hide yes)
			(effects
				(font
					(size 1.27 1.27)
				)
				(justify mirror)
			)
		)
		(property "Value" ""
			(at 0 0 90)
			(layer "B.Fab")
			(effects
				(font
					(size 1.27 1.27)
				)
				(justify mirror)
			)
		)
		(duplicate_pad_numbers_are_jumpers no)
		(fp_line
			(start -0.299974 0.150114)
			(end 0.299974 0.150114)
			(stroke
				(width 0.1)
				(type default)
			)
			(layer "B.Fab")
		)
		(fp_line
			(start 0.299974 0.150114)
			(end 0.299974 -0.150114)
			(stroke
				(width 0.1)
				(type default)
			)
			(layer "B.Fab")
		)
		(fp_line
			(start -0.299974 -0.150114)
			(end -0.299974 0.150114)
			(stroke
				(width 0.1)
				(type default)
			)
			(layer "B.Fab")
		)
		(fp_line
			(start 0.299974 -0.150114)
			(end -0.299974 -0.150114)
			(stroke
				(width 0.1)
				(type default)
			)
			(layer "B.Fab")
		)
		(pad "1" smd rect
			(at 0.2667 0 90)
			(size 0.3048 0.381)
			(layers "B.Cu" "B.Mask" "B.Paste")
			(net "P0V9_CPU1_RT3_2A_2D")
		)
		(pad "2" smd rect
			(at -0.2667 0 90)
			(size 0.3048 0.381)
			(layers "B.Cu" "B.Mask" "B.Paste")
			(net "GND")
		)
	)
	(footprint ""
		(layer "B.Cu")
		(at 320.272664 -73.534778)
		(property "Reference" "Q78"
			(at 1.4224 -1.768348 0)
			(unlocked yes)
			(layer "B.SilkS")
			(effects
				(font
					(size 0.7874 0.5842)
					(thickness 0.1524)
				)
				(justify left mirror)
			)
		)
		(property "Value" ""
			(at 0 0 0)
			(layer "B.Fab")
			(effects
				(font
					(size 1.27 1.27)
				)
				(justify mirror)
			)
		)
		(duplicate_pad_numbers_are_jumpers no)
		(fp_line
			(start -1.332738 -1.100074)
			(end -1.332738 1.100074)
			(stroke
				(width 0.1524)
				(type default)
			)
			(layer "B.SilkS")
		)
		(fp_line
			(start -1.332738 1.100074)
			(end 1.332738 1.100074)
			(stroke
				(width 0.1524)
				(type default)
			)
			(layer "B.SilkS")
		)
		(fp_line
			(start -0.4826 -1.100074)
			(end -1.332738 -1.100074)
			(stroke
				(width 0.1524)
				(type default)
			)
			(layer "B.SilkS")
		)
		(fp_line
			(start 0 -0.541274)
			(end -0.4826 -1.100074)
			(stroke
				(width 0.1524)
				(type default)
			)
			(layer "B.SilkS")
		)
		(fp_line
			(start 0.4826 -1.100074)
			(end 0 -0.541274)
			(stroke
				(width 0.1524)
				(type default)
			)
			(layer "B.SilkS")
		)
		(fp_line
			(start 1.332738 -1.100074)
			(end 0.4826 -1.100074)
			(stroke
				(width 0.1524)
				(type default)
			)
			(layer "B.SilkS")
		)
		(fp_line
			(start 1.332738 1.100074)
			(end 1.332738 -1.100074)
			(stroke
				(width 0.1524)
				(type default)
			)
			(layer "B.SilkS")
		)
		(fp_poly
			(pts
				(xy 1.489456 -1.189482) (xy 1.737614 -1.933956) (xy 2.23393 -1.43764)
			)
			(stroke
				(width 0)
				(type default)
			)
			(fill yes)
			(layer "B.SilkS")
		)
		(fp_line
			(start -0.674878 -1.100074)
			(end -0.674878 1.100074)
			(stroke
				(width 0.1)
				(type default)
			)
			(layer "B.Fab")
		)
		(fp_line
			(start -0.674878 1.100074)
			(end 0.674878 1.100074)
			(stroke
				(width 0.1)
				(type default)
			)
			(layer "B.Fab")
		)
		(fp_line
			(start 0.674878 -1.100074)
			(end -0.674878 -1.100074)
			(stroke
				(width 0.1)
				(type default)
			)
			(layer "B.Fab")
		)
		(fp_line
			(start 0.674878 1.100074)
			(end 0.674878 -1.100074)
			(stroke
				(width 0.1)
				(type default)
			)
			(layer "B.Fab")
		)
		(fp_poly
			(pts
				(xy 2.2352 -0.298958) (xy 2.2352 -1.001014) (xy 1.533144 -0.649986)
			)
			(stroke
				(width 0)
				(type default)
			)
			(fill yes)
			(layer "B.Fab")
		)
		(pad "1" smd rect
			(at 0.94996 -0.649986 90)
			(size 0.4318 0.508)
			(layers "B.Cu" "B.Mask" "B.Paste")
			(net "GND")
		)
		(pad "2" smd rect
			(at 0.94996 0 90)
			(size 0.4318 0.508)
			(layers "B.Cu" "B.Mask" "B.Paste")
			(net "PWRGD_P1V8_AUX_R")
		)
		(pad "3" smd rect
			(at 0.94996 0.649986 90)
			(size 0.4318 0.508)
			(layers "B.Cu" "B.Mask" "B.Paste")
			(net "LED_PWRGD_PS_PWROK_PLD_D")
		)
		(pad "4" smd rect
			(at -0.94996 0.649986 90)
			(size 0.4318 0.508)
			(layers "B.Cu" "B.Mask" "B.Paste")
			(net "GND")
		)
		(pad "5" smd rect
			(at -0.94996 0 90)
			(size 0.4318 0.508)
			(layers "B.Cu" "B.Mask" "B.Paste")
			(net "PWRGD_PS_PWROK_PLD")
		)
		(pad "6" smd rect
			(at -0.94996 -0.649986 90)
			(size 0.4318 0.508)
			(layers "B.Cu" "B.Mask" "B.Paste")
			(net "LED_PWRGD_P1V8_AUX_D")
		)
	)
)
